(kicad_pcb
	(version 20260206)
	(generator "pcbnew")
	(generator_version "10.0")
	(general
		(thickness 1.6)
		(legacy_teardrops no)
	)
	(paper "A4")
	(title_block
		(title "Bryce Canyon_IOM_IOC_16318-2_OCP.brd")
		(comment 1 "Bryce Canyon / footprints 1131-1138 of 1605")
	)
	(layers
		(0 "F.Cu" signal "TOP")
		(4 "In1.Cu" signal "L2GND")
		(6 "In2.Cu" signal "L3")
		(8 "In3.Cu" signal "L4VCC")
		(10 "In4.Cu" signal "L5VCC")
		(12 "In5.Cu" signal "L6")
		(14 "In6.Cu" signal "L7GND")
		(2 "B.Cu" signal "BOTTOM")
		(9 "F.Adhes" user "F.Adhesive")
		(11 "B.Adhes" user "B.Adhesive")
		(13 "F.Paste" user "Package Geometry/Pastemask Top")
		(15 "B.Paste" user "Package Geometry/Pastemask Bottom")
		(5 "F.SilkS" user "Ref Des/Silkscreen Top")
		(7 "B.SilkS" user "Ref Des/Silkscreen Bottom")
		(1 "F.Mask" user "Board Geometry/Soldermask Top")
		(3 "B.Mask" user "Board Geometry/Soldermask Bottom")
		(17 "Dwgs.User" user "User.Drawings")
		(19 "Cmts.User" user "User.Comments")
		(21 "Eco1.User" user "User.Eco1")
		(23 "Eco2.User" user "User.Eco2")
		(25 "Edge.Cuts" user "Board Geometry/Outline")
		(27 "Margin" user)
		(31 "F.CrtYd" user "Package Geometry/Place Bound Top")
		(29 "B.CrtYd" user "Package Geometry/Place Bound Bottom")
		(35 "F.Fab" user "Ref Des/Assembly Top")
		(33 "B.Fab" user "Ref Des/Assembly Bottom")
	)
	(footprint ""
		(layer "B.Cu")
		(at 95.4024 -152.7556 180)
		(property "Reference" "C13"
			(at 0 0 0)
			(layer "B.SilkS")
			(hide yes)
			(effects
				(font
					(size 1.27 1.27)
				)
				(justify mirror)
			)
		)
		(property "Value" "SC1U16V3KX-5GP"
			(at 0 -2.8194 180)
			(unlocked yes)
			(layer "B.Fab")
			(hide yes)
			(effects
				(font
					(size 1.016 1.016)
					(thickness 0.1524)
				)
				(justify mirror)
			)
		)
		(property "Device Type" "C603H36"
			(at 0 -4.3434 180)
			(unlocked yes)
			(layer "B.Fab")
			(hide yes)
			(effects
				(font
					(size 1.016 1.016)
					(thickness 0.1524)
				)
				(justify mirror)
			)
		)
		(duplicate_pad_numbers_are_jumpers no)
		(fp_line
			(start -0.508 0)
			(end 0.508 0)
			(stroke
				(width 0.2032)
				(type default)
			)
			(layer "B.SilkS")
		)
		(fp_rect
			(start 0.5842 1.3335)
			(end -0.5842 -1.3335)
			(stroke
				(width 0)
				(type default)
			)
			(fill no)
			(layer "B.CrtYd")
		)
		(fp_rect
			(start 0.5842 1.3335)
			(end -0.5842 -1.3335)
			(stroke
				(width 0)
				(type default)
			)
			(fill no)
			(layer "B.Fab")
		)
		(pad "1" smd custom
			(at 0 -0.762)
			(size 0.2159 0.2159)
			(layers "B.Cu" "B.Mask" "B.Paste")
			(net "P3V3_STBY")
			(options
				(clearance outline)
				(anchor circle)
			)
			(primitives
				(gr_poly
					(pts
						(arc
							(start -0.3302 0.4318)
							(mid -0.402042 0.402042)
							(end -0.4318 0.3302)
						)
						(arc
							(start -0.4318 -0.3302)
							(mid -0.402042 -0.402042)
							(end -0.3302 -0.4318)
						)
						(arc
							(start 0.3302 -0.4318)
							(mid 0.402042 -0.402042)
							(end 0.4318 -0.3302)
						)
						(arc
							(start 0.4318 0.3302)
							(mid 0.402042 0.402042)
							(end 0.3302 0.4318)
						)
					)
					(width 0)
					(fill yes)
				)
			)
		)
		(pad "2" smd custom
			(at 0 0.762)
			(size 0.2159 0.2159)
			(layers "B.Cu" "B.Mask" "B.Paste")
			(net "GND")
			(options
				(clearance outline)
				(anchor circle)
			)
			(primitives
				(gr_poly
					(pts
						(arc
							(start -0.3302 0.4318)
							(mid -0.402042 0.402042)
							(end -0.4318 0.3302)
						)
						(arc
							(start -0.4318 -0.3302)
							(mid -0.402042 -0.402042)
							(end -0.3302 -0.4318)
						)
						(arc
							(start 0.3302 -0.4318)
							(mid 0.402042 -0.402042)
							(end 0.4318 -0.3302)
						)
						(arc
							(start 0.4318 0.3302)
							(mid 0.402042 0.402042)
							(end 0.3302 0.4318)
						)
					)
					(width 0)
					(fill yes)
				)
			)
		)
	)
	(footprint ""
		(layer "B.Cu")
		(at 129.00533 -14.629638)
		(property "Reference" "C145"
			(at 0 0 0)
			(layer "B.SilkS")
			(hide yes)
			(effects
				(font
					(size 1.27 1.27)
				)
				(justify mirror)
			)
		)
		(property "Value" "SC1U16V3KX-5GP"
			(at 0 -2.8194 0)
			(unlocked yes)
			(layer "B.Fab")
			(hide yes)
			(effects
				(font
					(size 1.016 1.016)
					(thickness 0.1524)
				)
				(justify mirror)
			)
		)
		(property "Device Type" "C603H36"
			(at 0 -4.3434 0)
			(unlocked yes)
			(layer "B.Fab")
			(hide yes)
			(effects
				(font
					(size 1.016 1.016)
					(thickness 0.1524)
				)
				(justify mirror)
			)
		)
		(duplicate_pad_numbers_are_jumpers no)
		(fp_line
			(start -0.508 0)
			(end 0.508 0)
			(stroke
				(width 0.2032)
				(type default)
			)
			(layer "B.SilkS")
		)
		(fp_rect
			(start 0.5842 1.3335)
			(end -0.5842 -1.3335)
			(stroke
				(width 0)
				(type default)
			)
			(fill no)
			(layer "B.CrtYd")
		)
		(fp_rect
			(start 0.5842 1.3335)
			(end -0.5842 -1.3335)
			(stroke
				(width 0)
				(type default)
			)
			(fill no)
			(layer "B.Fab")
		)
		(pad "1" smd custom
			(at 0 -0.762 180)
			(size 0.2159 0.2159)
			(layers "B.Cu" "B.Mask" "B.Paste")
			(net "MB0_CM_UV_R")
			(options
				(clearance outline)
				(anchor circle)
			)
			(primitives
				(gr_poly
					(pts
						(arc
							(start -0.3302 0.4318)
							(mid -0.402042 0.402042)
							(end -0.4318 0.3302)
						)
						(arc
							(start -0.4318 -0.3302)
							(mid -0.402042 -0.402042)
							(end -0.3302 -0.4318)
						)
						(arc
							(start 0.3302 -0.4318)
							(mid 0.402042 -0.402042)
							(end 0.4318 -0.3302)
						)
						(arc
							(start 0.4318 0.3302)
							(mid 0.402042 0.402042)
							(end 0.3302 0.4318)
						)
					)
					(width 0)
					(fill yes)
				)
			)
		)
		(pad "2" smd custom
			(at 0 0.762 180)
			(size 0.2159 0.2159)
			(layers "B.Cu" "B.Mask" "B.Paste")
			(net "AGND_CURRENT_MON")
			(options
				(clearance outline)
				(anchor circle)
			)
			(primitives
				(gr_poly
					(pts
						(arc
							(start -0.3302 0.4318)
							(mid -0.402042 0.402042)
							(end -0.4318 0.3302)
						)
						(arc
							(start -0.4318 -0.3302)
							(mid -0.402042 -0.402042)
							(end -0.3302 -0.4318)
						)
						(arc
							(start 0.3302 -0.4318)
							(mid 0.402042 -0.402042)
							(end 0.4318 -0.3302)
						)
						(arc
							(start 0.4318 0.3302)
							(mid 0.402042 0.402042)
							(end 0.3302 0.4318)
						)
					)
					(width 0)
					(fill yes)
				)
			)
		)
	)
	(footprint ""
		(layer "B.Cu")
		(at 40.4622 -134.112 180)
		(property "Reference" "R375"
			(at 0 0 0)
			(layer "B.SilkS")
			(hide yes)
			(effects
				(font
					(size 1.27 1.27)
				)
				(justify mirror)
			)
		)
		(property "Value" "4K7R2F-GP"
			(at -0.064008 -3.993896 180)
			(unlocked yes)
			(layer "B.Fab")
			(hide yes)
			(effects
				(font
					(size 1.016 1.016)
					(thickness 0.1524)
				)
				(justify mirror)
			)
		)
		(property "Device Type" "R402H16"
			(at -0.064008 -5.517896 180)
			(unlocked yes)
			(layer "B.Fab")
			(hide yes)
			(effects
				(font
					(size 1.016 1.016)
					(thickness 0.1524)
				)
				(justify mirror)
			)
		)
		(duplicate_pad_numbers_are_jumpers no)
		(fp_line
			(start 0.508 -0.9398)
			(end 0.508 0.9398)
			(stroke
				(width 0.1524)
				(type default)
			)
			(layer "B.SilkS")
		)
		(fp_line
			(start -0.508 -0.9398)
			(end 0.508 -0.9398)
			(stroke
				(width 0.1524)
				(type default)
			)
			(layer "B.SilkS")
		)
		(fp_rect
			(start 0.508 0.9398)
			(end -0.508 -0.9398)
			(stroke
				(width 0)
				(type default)
			)
			(fill no)
			(layer "B.CrtYd")
		)
		(fp_rect
			(start 0.508 0.9398)
			(end -0.508 -0.9398)
			(stroke
				(width 0)
				(type default)
			)
			(fill no)
			(layer "B.Fab")
		)
		(pad "1" smd custom
			(at 0 -0.4445)
			(size 0.1397 0.1397)
			(layers "B.Cu" "B.Mask" "B.Paste")
			(net "P3V3_STBY")
			(options
				(clearance outline)
				(anchor circle)
			)
			(primitives
				(gr_poly
					(pts
						(arc
							(start -0.1778 0.2794)
							(mid -0.249642 0.249642)
							(end -0.2794 0.1778)
						)
						(arc
							(start -0.2794 -0.1778)
							(mid -0.249642 -0.249642)
							(end -0.1778 -0.2794)
						)
						(arc
							(start 0.1778 -0.2794)
							(mid 0.249642 -0.249642)
							(end 0.2794 -0.1778)
						)
						(arc
							(start 0.2794 0.1778)
							(mid 0.249642 0.249642)
							(end 0.1778 0.2794)
						)
					)
					(width 0)
					(fill yes)
				)
			)
		)
		(pad "2" smd custom
			(at 0 0.4445)
			(size 0.1397 0.1397)
			(layers "B.Cu" "B.Mask" "B.Paste")
			(net "BMC_GPIOS7")
			(options
				(clearance outline)
				(anchor circle)
			)
			(primitives
				(gr_poly
					(pts
						(arc
							(start -0.1778 0.2794)
							(mid -0.249642 0.249642)
							(end -0.2794 0.1778)
						)
						(arc
							(start -0.2794 -0.1778)
							(mid -0.249642 -0.249642)
							(end -0.1778 -0.2794)
						)
						(arc
							(start 0.1778 -0.2794)
							(mid 0.249642 -0.249642)
							(end 0.2794 -0.1778)
						)
						(arc
							(start 0.2794 0.1778)
							(mid 0.249642 0.249642)
							(end 0.1778 0.2794)
						)
					)
					(width 0)
					(fill yes)
				)
			)
		)
	)
	(footprint ""
		(layer "B.Cu")
		(at 204.411072 -68.748656 -90)
		(property "Reference" "C352"
			(at 0 0 90)
			(layer "B.SilkS")
			(hide yes)
			(effects
				(font
					(size 1.27 1.27)
				)
				(justify mirror)
			)
		)
		(property "Value" "SC1U6D3V1MX-GP"
			(at -1.9177 2.0193 270)
			(unlocked yes)
			(layer "B.Fab")
			(hide yes)
			(effects
				(font
					(size 1.016 1.016)
					(thickness 0.1524)
				)
				(justify mirror)
			)
		)
		(property "Device Type" "C0201H14"
			(at -1.9177 0.4953 270)
			(unlocked yes)
			(layer "B.Fab")
			(hide yes)
			(effects
				(font
					(size 1.016 1.016)
					(thickness 0.1524)
				)
				(justify mirror)
			)
		)
		(duplicate_pad_numbers_are_jumpers no)
		(fp_rect
			(start 0.1524 0.3048)
			(end -0.1524 -0.3048)
			(stroke
				(width 0)
				(type default)
			)
			(fill no)
			(layer "B.CrtYd")
		)
		(fp_poly
			(pts
				(xy 0.2794 0.6477) (xy 0.2794 -0.6477) (xy -0.2794 -0.6477) (xy -0.2794 -0.1905) (xy -0.1524 -0.1905)
				(xy -0.1524 -0.3048) (xy 0.1524 -0.3048) (xy 0.1524 0.3048) (xy -0.1524 0.3048) (xy -0.1524 -0.1778)
				(xy -0.2794 -0.1778) (xy -0.2794 0.6477)
			)
			(stroke
				(width 0)
				(type default)
			)
			(fill no)
			(layer "B.CrtYd")
		)
		(fp_rect
			(start 0.2794 0.6477)
			(end -0.2794 -0.6477)
			(stroke
				(width 0)
				(type default)
			)
			(fill no)
			(layer "B.Fab")
		)
		(pad "1" smd custom
			(at 0 -0.2794 90)
			(size 0.0762 0.0762)
			(layers "B.Cu" "B.Mask" "B.Paste")
			(net "SAS0_VDDH")
			(options
				(clearance outline)
				(anchor circle)
			)
			(primitives
				(gr_poly
					(pts
						(arc
							(start 0.1524 0.127)
							(mid 0.137521 0.162921)
							(end 0.1016 0.1778)
						)
						(arc
							(start -0.1016 0.1778)
							(mid -0.137521 0.162921)
							(end -0.1524 0.127)
						)
						(arc
							(start -0.1524 -0.127)
							(mid -0.137521 -0.162921)
							(end -0.1016 -0.1778)
						)
						(arc
							(start 0.1016 -0.1778)
							(mid 0.137521 -0.162921)
							(end 0.1524 -0.127)
						)
					)
					(width 0)
					(fill yes)
				)
			)
		)
		(pad "2" smd custom
			(at 0 0.2794 90)
			(size 0.0762 0.0762)
			(layers "B.Cu" "B.Mask" "B.Paste")
			(net "GND")
			(options
				(clearance outline)
				(anchor circle)
			)
			(primitives
				(gr_poly
					(pts
						(arc
							(start 0.1524 0.127)
							(mid 0.137521 0.162921)
							(end 0.1016 0.1778)
						)
						(arc
							(start -0.1016 0.1778)
							(mid -0.137521 0.162921)
							(end -0.1524 0.127)
						)
						(arc
							(start -0.1524 -0.127)
							(mid -0.137521 -0.162921)
							(end -0.1016 -0.1778)
						)
						(arc
							(start 0.1016 -0.1778)
							(mid 0.137521 -0.162921)
							(end 0.1524 -0.127)
						)
					)
					(width 0)
					(fill yes)
				)
			)
		)
	)
	(footprint ""
		(layer "B.Cu")
		(at 193.802 -45.9232 90)
		(property "Reference" "R679"
			(at 0 0 90)
			(layer "B.SilkS")
			(hide yes)
			(effects
				(font
					(size 1.27 1.27)
				)
				(justify mirror)
			)
		)
		(property "Value" "10R2F-L-GP"
			(at -0.064008 -3.993896 90)
			(unlocked yes)
			(layer "B.Fab")
			(hide yes)
			(effects
				(font
					(size 1.016 1.016)
					(thickness 0.1524)
				)
				(justify mirror)
			)
		)
		(property "Device Type" "R402H14"
			(at -0.064008 -5.517896 90)
			(unlocked yes)
			(layer "B.Fab")
			(hide yes)
			(effects
				(font
					(size 1.016 1.016)
					(thickness 0.1524)
				)
				(justify mirror)
			)
		)
		(duplicate_pad_numbers_are_jumpers no)
		(fp_line
			(start 0.508 -0.9398)
			(end 0.508 0.9398)
			(stroke
				(width 0.1524)
				(type default)
			)
			(layer "B.SilkS")
		)
		(fp_line
			(start -0.508 -0.9398)
			(end 0.508 -0.9398)
			(stroke
				(width 0.1524)
				(type default)
			)
			(layer "B.SilkS")
		)
		(fp_rect
			(start 0.508 0.9398)
			(end -0.508 -0.9398)
			(stroke
				(width 0)
				(type default)
			)
			(fill no)
			(layer "B.CrtYd")
		)
		(fp_rect
			(start 0.508 0.9398)
			(end -0.508 -0.9398)
			(stroke
				(width 0)
				(type default)
			)
			(fill no)
			(layer "B.Fab")
		)
		(pad "1" smd custom
			(at 0 -0.4445 270)
			(size 0.1397 0.1397)
			(layers "B.Cu" "B.Mask" "B.Paste")
			(net "P1V8")
			(options
				(clearance outline)
				(anchor circle)
			)
			(primitives
				(gr_poly
					(pts
						(arc
							(start -0.1778 0.2794)
							(mid -0.249642 0.249642)
							(end -0.2794 0.1778)
						)
						(arc
							(start -0.2794 -0.1778)
							(mid -0.249642 -0.249642)
							(end -0.1778 -0.2794)
						)
						(arc
							(start 0.1778 -0.2794)
							(mid 0.249642 -0.249642)
							(end 0.2794 -0.1778)
						)
						(arc
							(start 0.2794 0.1778)
							(mid 0.249642 0.249642)
							(end 0.1778 0.2794)
						)
					)
					(width 0)
					(fill yes)
				)
			)
		)
		(pad "2" smd custom
			(at 0 0.4445 270)
			(size 0.1397 0.1397)
			(layers "B.Cu" "B.Mask" "B.Paste")
			(net "HM40ADC_VDDA")
			(options
				(clearance outline)
				(anchor circle)
			)
			(primitives
				(gr_poly
					(pts
						(arc
							(start -0.1778 0.2794)
							(mid -0.249642 0.249642)
							(end -0.2794 0.1778)
						)
						(arc
							(start -0.2794 -0.1778)
							(mid -0.249642 -0.249642)
							(end -0.1778 -0.2794)
						)
						(arc
							(start 0.1778 -0.2794)
							(mid 0.249642 -0.249642)
							(end 0.2794 -0.1778)
						)
						(arc
							(start 0.2794 0.1778)
							(mid 0.249642 0.249642)
							(end 0.1778 0.2794)
						)
					)
					(width 0)
					(fill yes)
				)
			)
		)
	)
	(footprint ""
		(layer "B.Cu")
		(at 39.751254 -142.892018 180)
		(property "Reference" "R145"
			(at 0 0 0)
			(layer "B.SilkS")
			(hide yes)
			(effects
				(font
					(size 1.27 1.27)
				)
				(justify mirror)
			)
		)
		(property "Value" "240R2F-1-GP"
			(at -0.064008 -3.993896 180)
			(unlocked yes)
			(layer "B.Fab")
			(hide yes)
			(effects
				(font
					(size 1.016 1.016)
					(thickness 0.1524)
				)
				(justify mirror)
			)
		)
		(property "Device Type" "R402H16"
			(at -0.064008 -5.517896 180)
			(unlocked yes)
			(layer "B.Fab")
			(hide yes)
			(effects
				(font
					(size 1.016 1.016)
					(thickness 0.1524)
				)
				(justify mirror)
			)
		)
		(duplicate_pad_numbers_are_jumpers no)
		(fp_line
			(start 0.508 -0.9398)
			(end 0.508 0.9398)
			(stroke
				(width 0.1524)
				(type default)
			)
			(layer "B.SilkS")
		)
		(fp_line
			(start -0.508 -0.9398)
			(end 0.508 -0.9398)
			(stroke
				(width 0.1524)
				(type default)
			)
			(layer "B.SilkS")
		)
		(fp_rect
			(start 0.508 0.9398)
			(end -0.508 -0.9398)
			(stroke
				(width 0)
				(type default)
			)
			(fill no)
			(layer "B.CrtYd")
		)
		(fp_rect
			(start 0.508 0.9398)
			(end -0.508 -0.9398)
			(stroke
				(width 0)
				(type default)
			)
			(fill no)
			(layer "B.Fab")
		)
		(pad "1" smd custom
			(at 0 -0.4445)
			(size 0.1397 0.1397)
			(layers "B.Cu" "B.Mask" "B.Paste")
			(net "GND")
			(options
				(clearance outline)
				(anchor circle)
			)
			(primitives
				(gr_poly
					(pts
						(arc
							(start -0.1778 0.2794)
							(mid -0.249642 0.249642)
							(end -0.2794 0.1778)
						)
						(arc
							(start -0.2794 -0.1778)
							(mid -0.249642 -0.249642)
							(end -0.1778 -0.2794)
						)
						(arc
							(start 0.1778 -0.2794)
							(mid 0.249642 -0.249642)
							(end 0.2794 -0.1778)
						)
						(arc
							(start 0.2794 0.1778)
							(mid 0.249642 0.249642)
							(end 0.1778 0.2794)
						)
					)
					(width 0)
					(fill yes)
				)
			)
		)
		(pad "2" smd custom
			(at 0 0.4445)
			(size 0.1397 0.1397)
			(layers "B.Cu" "B.Mask" "B.Paste")
			(net "MIOZ")
			(options
				(clearance outline)
				(anchor circle)
			)
			(primitives
				(gr_poly
					(pts
						(arc
							(start -0.1778 0.2794)
							(mid -0.249642 0.249642)
							(end -0.2794 0.1778)
						)
						(arc
							(start -0.2794 -0.1778)
							(mid -0.249642 -0.249642)
							(end -0.1778 -0.2794)
						)
						(arc
							(start 0.1778 -0.2794)
							(mid 0.249642 -0.249642)
							(end 0.2794 -0.1778)
						)
						(arc
							(start 0.2794 0.1778)
							(mid 0.249642 0.249642)
							(end 0.1778 0.2794)
						)
					)
					(width 0)
					(fill yes)
				)
			)
		)
	)
	(footprint ""
		(layer "B.Cu")
		(at 58.970418 -140.960348)
		(property "Reference" "TP15"
			(at 0 0 0)
			(layer "B.SilkS")
			(hide yes)
			(effects
				(font
					(size 1.27 1.27)
				)
				(justify mirror)
			)
		)
		(property "Value" "TPAD28-2-GP"
			(at 0.0127 -1.6637 0)
			(unlocked yes)
			(layer "B.Fab")
			(hide yes)
			(effects
				(font
					(size 1.016 1.016)
					(thickness 0.1524)
				)
				(justify mirror)
			)
		)
		(property "Device Type" "TPAD28"
			(at 0.0127 -3.1877 0)
			(unlocked yes)
			(layer "B.Fab")
			(hide yes)
			(effects
				(font
					(size 1.016 1.016)
					(thickness 0.1524)
				)
				(justify mirror)
			)
		)
		(duplicate_pad_numbers_are_jumpers no)
		(fp_poly
			(pts
				(arc
					(start 0.3556 0)
					(mid -0.3556 0)
					(end 0.3556 0)
				)
			)
			(stroke
				(width 0)
				(type default)
			)
			(fill no)
			(layer "B.CrtYd")
		)
		(fp_poly
			(pts
				(arc
					(start 0.6096 0)
					(mid -0.6096 0)
					(end 0.6096 0)
				)
			)
			(stroke
				(width 0)
				(type default)
			)
			(fill no)
			(layer "B.Fab")
		)
		(pad "1" smd circle
			(at 0 0 180)
			(size 0.7112 0.7112)
			(layers "B.Cu" "B.Mask" "B.Paste")
			(net "I2C_M2_2_SCL")
		)
	)
	(footprint ""
		(layer "B.Cu")
		(at 189.8904 -55.5752 90)
		(property "Reference" "C433"
			(at 0 0 90)
			(layer "B.SilkS")
			(hide yes)
			(effects
				(font
					(size 1.27 1.27)
				)
				(justify mirror)
			)
		)
		(property "Value" "SCD1U16V2KX-3GP"
			(at -1.1811 -2.7051 90)
			(unlocked yes)
			(layer "B.Fab")
			(hide yes)
			(effects
				(font
					(size 1.016 1.016)
					(thickness 0.1524)
				)
				(justify mirror)
			)
		)
		(property "Device Type" "C402H22"
			(at -1.1811 -4.2291 90)
			(unlocked yes)
			(layer "B.Fab")
			(hide yes)
			(effects
				(font
					(size 1.016 1.016)
					(thickness 0.1524)
				)
				(justify mirror)
			)
		)
		(duplicate_pad_numbers_are_jumpers no)
		(fp_rect
			(start 0.4318 0.9525)
			(end -0.4318 -0.9525)
			(stroke
				(width 0)
				(type default)
			)
			(fill no)
			(layer "B.CrtYd")
		)
		(fp_rect
			(start 0.4318 0.9525)
			(end -0.4318 -0.9525)
			(stroke
				(width 0)
				(type default)
			)
			(fill no)
			(layer "B.Fab")
		)
		(pad "1" smd custom
			(at 0 -0.4445 270)
			(size 0.1524 0.1524)
			(layers "B.Cu" "B.Mask" "B.Paste")
			(net "P1V8")
			(options
				(clearance outline)
				(anchor circle)
			)
			(primitives
				(gr_poly
					(pts
						(arc
							(start 0.3048 0.2032)
							(mid 0.275042 0.275042)
							(end 0.2032 0.3048)
						)
						(arc
							(start -0.2032 0.3048)
							(mid -0.275042 0.275042)
							(end -0.3048 0.2032)
						)
						(arc
							(start -0.3048 -0.2032)
							(mid -0.275042 -0.275042)
							(end -0.2032 -0.3048)
						)
						(arc
							(start 0.2032 -0.3048)
							(mid 0.275042 -0.275042)
							(end 0.3048 -0.2032)
						)
					)
					(width 0)
					(fill yes)
				)
			)
		)
		(pad "2" smd custom
			(at 0 0.4445 270)
			(size 0.1524 0.1524)
			(layers "B.Cu" "B.Mask" "B.Paste")
			(net "GND")
			(options
				(clearance outline)
				(anchor circle)
			)
			(primitives
				(gr_poly
					(pts
						(arc
							(start 0.3048 0.2032)
							(mid 0.275042 0.275042)
							(end 0.2032 0.3048)
						)
						(arc
							(start -0.2032 0.3048)
							(mid -0.275042 0.275042)
							(end -0.3048 0.2032)
						)
						(arc
							(start -0.3048 -0.2032)
							(mid -0.275042 -0.275042)
							(end -0.2032 -0.3048)
						)
						(arc
							(start 0.2032 -0.3048)
							(mid 0.275042 -0.275042)
							(end 0.3048 -0.2032)
						)
					)
					(width 0)
					(fill yes)
				)
			)
		)
	)
)
